(kicad_pcb
	(version 20260206)
	(generator "pcbnew")
	(generator_version "10.0")
	(general
		(thickness 1.6)
		(legacy_teardrops no)
	)
	(paper "A4")
	(title_block
		(title "03242023_DA0F0TMBIJ0_F0T_Motherboard_J_brd_V01_OCP.brd")
		(comment 1 "Grand Teton / footprints 3171-3176 of 6105")
	)
	(layers
		(0 "F.Cu" signal "TOP")
		(4 "In1.Cu" signal "GND")
		(6 "In2.Cu" signal "IN1")
		(8 "In3.Cu" signal "GND1")
		(10 "In4.Cu" signal "IN2")
		(12 "In5.Cu" signal "GND2")
		(14 "In6.Cu" signal "IN3")
		(16 "In7.Cu" signal "GND3")
		(18 "In8.Cu" signal "VCC")
		(20 "In9.Cu" signal "VCC1")
		(22 "In10.Cu" signal "GND4")
		(24 "In11.Cu" signal "IN4")
		(26 "In12.Cu" signal "GND5")
		(28 "In13.Cu" signal "IN5")
		(30 "In14.Cu" signal "GND6")
		(32 "In15.Cu" signal "IN6")
		(34 "In16.Cu" signal "GND7")
		(2 "B.Cu" signal "BOTTOM")
		(9 "F.Adhes" user "F.Adhesive")
		(11 "B.Adhes" user "B.Adhesive")
		(13 "F.Paste" user "Package Geometry/Pastemask Top")
		(15 "B.Paste" user "Package Geometry/Pastemask Bottom")
		(5 "F.SilkS" user "Ref Des/Silkscreen Top")
		(7 "B.SilkS" user "Ref Des/Silkscreen Bottom")
		(1 "F.Mask" user "Board Geometry/Soldermask Top")
		(3 "B.Mask" user "Board Geometry/Soldermask Bottom")
		(17 "Dwgs.User" user "User.Drawings")
		(19 "Cmts.User" user "User.Comments")
		(21 "Eco1.User" user "User.Eco1")
		(23 "Eco2.User" user "User.Eco2")
		(25 "Edge.Cuts" user "Board Geometry/Outline")
		(27 "Margin" user)
		(31 "F.CrtYd" user "Package Geometry/Place Bound Top")
		(29 "B.CrtYd" user "Package Geometry/Place Bound Bottom")
		(35 "F.Fab" user "Ref Des/Assembly Top")
		(33 "B.Fab" user "Ref Des/Assembly Bottom")
	)
	(footprint ""
		(layer "F.Cu")
		(at 351.961704 -353.14509)
		(property "Reference" "PR170"
			(at 0 0 0)
			(layer "F.SilkS")
			(hide yes)
			(effects
				(font
					(size 1.27 1.27)
				)
			)
		)
		(property "Value" ""
			(at 0 0 0)
			(layer "F.Fab")
			(effects
				(font
					(size 1.27 1.27)
				)
			)
		)
		(duplicate_pad_numbers_are_jumpers no)
		(fp_line
			(start -0.7874 -0.4064)
			(end 0.7874 -0.4064)
			(stroke
				(width 0.1524)
				(type default)
			)
			(layer "F.SilkS")
		)
		(fp_line
			(start -0.7874 0.4064)
			(end -0.7874 -0.4064)
			(stroke
				(width 0.1524)
				(type default)
			)
			(layer "F.SilkS")
		)
		(fp_line
			(start 0.7874 -0.4064)
			(end 0.7874 0.4064)
			(stroke
				(width 0.1524)
				(type default)
			)
			(layer "F.SilkS")
		)
		(fp_line
			(start 0.7874 0.4064)
			(end -0.7874 0.4064)
			(stroke
				(width 0.1524)
				(type default)
			)
			(layer "F.SilkS")
		)
		(fp_line
			(start -0.67945 -0.305054)
			(end -0.12065 -0.305054)
			(stroke
				(width 0.1)
				(type default)
			)
			(layer "F.Fab")
		)
		(fp_line
			(start -0.67945 0.3048)
			(end -0.67945 -0.305054)
			(stroke
				(width 0.1)
				(type default)
			)
			(layer "F.Fab")
		)
		(fp_line
			(start -0.12065 -0.305054)
			(end -0.12065 -0.2794)
			(stroke
				(width 0.1)
				(type default)
			)
			(layer "F.Fab")
		)
		(fp_line
			(start -0.12065 -0.2794)
			(end 0.12065 -0.2794)
			(stroke
				(width 0.1)
				(type default)
			)
			(layer "F.Fab")
		)
		(fp_line
			(start -0.12065 0.2794)
			(end -0.12065 0.3048)
			(stroke
				(width 0.1)
				(type default)
			)
			(layer "F.Fab")
		)
		(fp_line
			(start -0.12065 0.3048)
			(end -0.67945 0.3048)
			(stroke
				(width 0.1)
				(type default)
			)
			(layer "F.Fab")
		)
		(fp_line
			(start 0.120396 0.2794)
			(end -0.12065 0.2794)
			(stroke
				(width 0.1)
				(type default)
			)
			(layer "F.Fab")
		)
		(fp_line
			(start 0.120396 0.3048)
			(end 0.120396 0.2794)
			(stroke
				(width 0.1)
				(type default)
			)
			(layer "F.Fab")
		)
		(fp_line
			(start 0.12065 -0.3048)
			(end 0.67945 -0.3048)
			(stroke
				(width 0.1)
				(type default)
			)
			(layer "F.Fab")
		)
		(fp_line
			(start 0.12065 -0.2794)
			(end 0.12065 -0.3048)
			(stroke
				(width 0.1)
				(type default)
			)
			(layer "F.Fab")
		)
		(fp_line
			(start 0.67945 -0.3048)
			(end 0.67945 0.3048)
			(stroke
				(width 0.1)
				(type default)
			)
			(layer "F.Fab")
		)
		(fp_line
			(start 0.67945 0.3048)
			(end 0.120396 0.3048)
			(stroke
				(width 0.1)
				(type default)
			)
			(layer "F.Fab")
		)
		(pad "1" smd circle
			(at -0.40005 0)
			(size 0 0)
			(layers "F.Cu" "F.Mask" "F.Paste")
			(net "SH_PVCCIN_CPU0")
		)
		(pad "2" smd circle
			(at 0.40005 0)
			(size 0 0)
			(layers "F.Cu" "F.Mask" "F.Paste")
			(net "SH_PVCCIN_CPU0_R")
		)
	)
	(footprint ""
		(layer "F.Cu")
		(at 147.08378 -126.291848 180)
		(property "Reference" "R3157"
			(at 0 0 180)
			(layer "F.SilkS")
			(hide yes)
			(effects
				(font
					(size 1.27 1.27)
				)
			)
		)
		(property "Value" ""
			(at 0 0 180)
			(layer "F.Fab")
			(effects
				(font
					(size 1.27 1.27)
				)
			)
		)
		(duplicate_pad_numbers_are_jumpers no)
		(fp_line
			(start 0.7874 0.4064)
			(end -0.7874 0.4064)
			(stroke
				(width 0.1524)
				(type default)
			)
			(layer "F.SilkS")
		)
		(fp_line
			(start 0.7874 -0.4064)
			(end 0.7874 0.4064)
			(stroke
				(width 0.1524)
				(type default)
			)
			(layer "F.SilkS")
		)
		(fp_line
			(start -0.7874 0.4064)
			(end -0.7874 -0.4064)
			(stroke
				(width 0.1524)
				(type default)
			)
			(layer "F.SilkS")
		)
		(fp_line
			(start -0.7874 -0.4064)
			(end 0.7874 -0.4064)
			(stroke
				(width 0.1524)
				(type default)
			)
			(layer "F.SilkS")
		)
		(fp_line
			(start 0.67945 0.3048)
			(end 0.120396 0.3048)
			(stroke
				(width 0.1)
				(type default)
			)
			(layer "F.Fab")
		)
		(fp_line
			(start 0.67945 -0.3048)
			(end 0.67945 0.3048)
			(stroke
				(width 0.1)
				(type default)
			)
			(layer "F.Fab")
		)
		(fp_line
			(start 0.12065 -0.2794)
			(end 0.12065 -0.3048)
			(stroke
				(width 0.1)
				(type default)
			)
			(layer "F.Fab")
		)
		(fp_line
			(start 0.12065 -0.3048)
			(end 0.67945 -0.3048)
			(stroke
				(width 0.1)
				(type default)
			)
			(layer "F.Fab")
		)
		(fp_line
			(start 0.120396 0.3048)
			(end 0.120396 0.2794)
			(stroke
				(width 0.1)
				(type default)
			)
			(layer "F.Fab")
		)
		(fp_line
			(start 0.120396 0.2794)
			(end -0.12065 0.2794)
			(stroke
				(width 0.1)
				(type default)
			)
			(layer "F.Fab")
		)
		(fp_line
			(start -0.12065 0.3048)
			(end -0.67945 0.3048)
			(stroke
				(width 0.1)
				(type default)
			)
			(layer "F.Fab")
		)
		(fp_line
			(start -0.12065 0.2794)
			(end -0.12065 0.3048)
			(stroke
				(width 0.1)
				(type default)
			)
			(layer "F.Fab")
		)
		(fp_line
			(start -0.12065 -0.2794)
			(end 0.12065 -0.2794)
			(stroke
				(width 0.1)
				(type default)
			)
			(layer "F.Fab")
		)
		(fp_line
			(start -0.12065 -0.305054)
			(end -0.12065 -0.2794)
			(stroke
				(width 0.1)
				(type default)
			)
			(layer "F.Fab")
		)
		(fp_line
			(start -0.67945 0.3048)
			(end -0.67945 -0.305054)
			(stroke
				(width 0.1)
				(type default)
			)
			(layer "F.Fab")
		)
		(fp_line
			(start -0.67945 -0.305054)
			(end -0.12065 -0.305054)
			(stroke
				(width 0.1)
				(type default)
			)
			(layer "F.Fab")
		)
		(pad "1" smd circle
			(at -0.40005 0 180)
			(size 0 0)
			(layers "F.Cu" "F.Mask" "F.Paste")
			(net "SMB_PEHPCPU1_LVC3_SDA")
		)
		(pad "2" smd circle
			(at 0.40005 0 180)
			(size 0 0)
			(layers "F.Cu" "F.Mask" "F.Paste")
			(net "SMB_PEHPCPU1_LVC3_R3_SDA")
		)
	)
	(footprint ""
		(layer "F.Cu")
		(at 220.100652 -105.226104 180)
		(property "Reference" "R2236"
			(at 0 0 180)
			(layer "F.SilkS")
			(hide yes)
			(effects
				(font
					(size 1.27 1.27)
				)
			)
		)
		(property "Value" ""
			(at 0 0 180)
			(layer "F.Fab")
			(effects
				(font
					(size 1.27 1.27)
				)
			)
		)
		(duplicate_pad_numbers_are_jumpers no)
		(fp_line
			(start 0.7874 0.4064)
			(end -0.7874 0.4064)
			(stroke
				(width 0.1524)
				(type default)
			)
			(layer "F.SilkS")
		)
		(fp_line
			(start 0.7874 -0.4064)
			(end 0.7874 0.4064)
			(stroke
				(width 0.1524)
				(type default)
			)
			(layer "F.SilkS")
		)
		(fp_line
			(start -0.7874 0.4064)
			(end -0.7874 -0.4064)
			(stroke
				(width 0.1524)
				(type default)
			)
			(layer "F.SilkS")
		)
		(fp_line
			(start -0.7874 -0.4064)
			(end 0.7874 -0.4064)
			(stroke
				(width 0.1524)
				(type default)
			)
			(layer "F.SilkS")
		)
		(fp_line
			(start 0.67945 0.3048)
			(end 0.120396 0.3048)
			(stroke
				(width 0.1)
				(type default)
			)
			(layer "F.Fab")
		)
		(fp_line
			(start 0.67945 -0.3048)
			(end 0.67945 0.3048)
			(stroke
				(width 0.1)
				(type default)
			)
			(layer "F.Fab")
		)
		(fp_line
			(start 0.12065 -0.2794)
			(end 0.12065 -0.3048)
			(stroke
				(width 0.1)
				(type default)
			)
			(layer "F.Fab")
		)
		(fp_line
			(start 0.12065 -0.3048)
			(end 0.67945 -0.3048)
			(stroke
				(width 0.1)
				(type default)
			)
			(layer "F.Fab")
		)
		(fp_line
			(start 0.120396 0.3048)
			(end 0.120396 0.2794)
			(stroke
				(width 0.1)
				(type default)
			)
			(layer "F.Fab")
		)
		(fp_line
			(start 0.120396 0.2794)
			(end -0.12065 0.2794)
			(stroke
				(width 0.1)
				(type default)
			)
			(layer "F.Fab")
		)
		(fp_line
			(start -0.12065 0.3048)
			(end -0.67945 0.3048)
			(stroke
				(width 0.1)
				(type default)
			)
			(layer "F.Fab")
		)
		(fp_line
			(start -0.12065 0.2794)
			(end -0.12065 0.3048)
			(stroke
				(width 0.1)
				(type default)
			)
			(layer "F.Fab")
		)
		(fp_line
			(start -0.12065 -0.2794)
			(end 0.12065 -0.2794)
			(stroke
				(width 0.1)
				(type default)
			)
			(layer "F.Fab")
		)
		(fp_line
			(start -0.12065 -0.305054)
			(end -0.12065 -0.2794)
			(stroke
				(width 0.1)
				(type default)
			)
			(layer "F.Fab")
		)
		(fp_line
			(start -0.67945 0.3048)
			(end -0.67945 -0.305054)
			(stroke
				(width 0.1)
				(type default)
			)
			(layer "F.Fab")
		)
		(fp_line
			(start -0.67945 -0.305054)
			(end -0.12065 -0.305054)
			(stroke
				(width 0.1)
				(type default)
			)
			(layer "F.Fab")
		)
		(pad "1" smd circle
			(at -0.40005 0 180)
			(size 0 0)
			(layers "F.Cu" "F.Mask" "F.Paste")
			(net "P12V_AUX")
		)
		(pad "2" smd circle
			(at 0.40005 0 180)
			(size 0 0)
			(layers "F.Cu" "F.Mask" "F.Paste")
			(net "A_HSC_INAP")
		)
	)
	(footprint ""
		(layer "F.Cu")
		(at 120.714008 -66.67754 90)
		(property "Reference" "R805"
			(at 0 0 90)
			(layer "F.SilkS")
			(hide yes)
			(effects
				(font
					(size 1.27 1.27)
				)
			)
		)
		(property "Value" ""
			(at 0 0 90)
			(layer "F.Fab")
			(effects
				(font
					(size 1.27 1.27)
				)
			)
		)
		(duplicate_pad_numbers_are_jumpers no)
		(fp_line
			(start 0.7874 -0.4064)
			(end 0.7874 0.4064)
			(stroke
				(width 0.1524)
				(type default)
			)
			(layer "F.SilkS")
		)
		(fp_line
			(start -0.7874 -0.4064)
			(end 0.7874 -0.4064)
			(stroke
				(width 0.1524)
				(type default)
			)
			(layer "F.SilkS")
		)
		(fp_line
			(start 0.7874 0.4064)
			(end -0.7874 0.4064)
			(stroke
				(width 0.1524)
				(type default)
			)
			(layer "F.SilkS")
		)
		(fp_line
			(start -0.7874 0.4064)
			(end -0.7874 -0.4064)
			(stroke
				(width 0.1524)
				(type default)
			)
			(layer "F.SilkS")
		)
		(fp_line
			(start -0.12065 -0.305054)
			(end -0.12065 -0.2794)
			(stroke
				(width 0.1)
				(type default)
			)
			(layer "F.Fab")
		)
		(fp_line
			(start -0.67945 -0.305054)
			(end -0.12065 -0.305054)
			(stroke
				(width 0.1)
				(type default)
			)
			(layer "F.Fab")
		)
		(fp_line
			(start 0.67945 -0.3048)
			(end 0.67945 0.3048)
			(stroke
				(width 0.1)
				(type default)
			)
			(layer "F.Fab")
		)
		(fp_line
			(start 0.12065 -0.3048)
			(end 0.67945 -0.3048)
			(stroke
				(width 0.1)
				(type default)
			)
			(layer "F.Fab")
		)
		(fp_line
			(start 0.12065 -0.2794)
			(end 0.12065 -0.3048)
			(stroke
				(width 0.1)
				(type default)
			)
			(layer "F.Fab")
		)
		(fp_line
			(start -0.12065 -0.2794)
			(end 0.12065 -0.2794)
			(stroke
				(width 0.1)
				(type default)
			)
			(layer "F.Fab")
		)
		(fp_line
			(start 0.120396 0.2794)
			(end -0.12065 0.2794)
			(stroke
				(width 0.1)
				(type default)
			)
			(layer "F.Fab")
		)
		(fp_line
			(start -0.12065 0.2794)
			(end -0.12065 0.3048)
			(stroke
				(width 0.1)
				(type default)
			)
			(layer "F.Fab")
		)
		(fp_line
			(start 0.67945 0.3048)
			(end 0.120396 0.3048)
			(stroke
				(width 0.1)
				(type default)
			)
			(layer "F.Fab")
		)
		(fp_line
			(start 0.120396 0.3048)
			(end 0.120396 0.2794)
			(stroke
				(width 0.1)
				(type default)
			)
			(layer "F.Fab")
		)
		(fp_line
			(start -0.12065 0.3048)
			(end -0.67945 0.3048)
			(stroke
				(width 0.1)
				(type default)
			)
			(layer "F.Fab")
		)
		(fp_line
			(start -0.67945 0.3048)
			(end -0.67945 -0.305054)
			(stroke
				(width 0.1)
				(type default)
			)
			(layer "F.Fab")
		)
		(pad "1" smd circle
			(at -0.40005 0 90)
			(size 0 0)
			(layers "F.Cu" "F.Mask" "F.Paste")
			(net "JTAG_PLD_TMS_R")
		)
		(pad "2" smd circle
			(at 0.40005 0 90)
			(size 0 0)
			(layers "F.Cu" "F.Mask" "F.Paste")
			(net "JTAG_BMC_PLD_TMS")
		)
	)
	(footprint ""
		(layer "F.Cu")
		(at 443.576964 -72.398128 90)
		(property "Reference" "PR389"
			(at 0 0 90)
			(layer "F.SilkS")
			(hide yes)
			(effects
				(font
					(size 1.27 1.27)
				)
			)
		)
		(property "Value" ""
			(at 0 0 90)
			(layer "F.Fab")
			(effects
				(font
					(size 1.27 1.27)
				)
			)
		)
		(duplicate_pad_numbers_are_jumpers no)
		(fp_line
			(start 0.7874 -0.4064)
			(end 0.7874 0.4064)
			(stroke
				(width 0.1524)
				(type default)
			)
			(layer "F.SilkS")
		)
		(fp_line
			(start -0.7874 -0.4064)
			(end 0.7874 -0.4064)
			(stroke
				(width 0.1524)
				(type default)
			)
			(layer "F.SilkS")
		)
		(fp_line
			(start 0.7874 0.4064)
			(end -0.7874 0.4064)
			(stroke
				(width 0.1524)
				(type default)
			)
			(layer "F.SilkS")
		)
		(fp_line
			(start -0.7874 0.4064)
			(end -0.7874 -0.4064)
			(stroke
				(width 0.1524)
				(type default)
			)
			(layer "F.SilkS")
		)
		(fp_line
			(start -0.12065 -0.305054)
			(end -0.12065 -0.2794)
			(stroke
				(width 0.1)
				(type default)
			)
			(layer "F.Fab")
		)
		(fp_line
			(start -0.67945 -0.305054)
			(end -0.12065 -0.305054)
			(stroke
				(width 0.1)
				(type default)
			)
			(layer "F.Fab")
		)
		(fp_line
			(start 0.67945 -0.3048)
			(end 0.67945 0.3048)
			(stroke
				(width 0.1)
				(type default)
			)
			(layer "F.Fab")
		)
		(fp_line
			(start 0.12065 -0.3048)
			(end 0.67945 -0.3048)
			(stroke
				(width 0.1)
				(type default)
			)
			(layer "F.Fab")
		)
		(fp_line
			(start 0.12065 -0.2794)
			(end 0.12065 -0.3048)
			(stroke
				(width 0.1)
				(type default)
			)
			(layer "F.Fab")
		)
		(fp_line
			(start -0.12065 -0.2794)
			(end 0.12065 -0.2794)
			(stroke
				(width 0.1)
				(type default)
			)
			(layer "F.Fab")
		)
		(fp_line
			(start 0.120396 0.2794)
			(end -0.12065 0.2794)
			(stroke
				(width 0.1)
				(type default)
			)
			(layer "F.Fab")
		)
		(fp_line
			(start -0.12065 0.2794)
			(end -0.12065 0.3048)
			(stroke
				(width 0.1)
				(type default)
			)
			(layer "F.Fab")
		)
		(fp_line
			(start 0.67945 0.3048)
			(end 0.120396 0.3048)
			(stroke
				(width 0.1)
				(type default)
			)
			(layer "F.Fab")
		)
		(fp_line
			(start 0.120396 0.3048)
			(end 0.120396 0.2794)
			(stroke
				(width 0.1)
				(type default)
			)
			(layer "F.Fab")
		)
		(fp_line
			(start -0.12065 0.3048)
			(end -0.67945 0.3048)
			(stroke
				(width 0.1)
				(type default)
			)
			(layer "F.Fab")
		)
		(fp_line
			(start -0.67945 0.3048)
			(end -0.67945 -0.305054)
			(stroke
				(width 0.1)
				(type default)
			)
			(layer "F.Fab")
		)
		(pad "1" smd circle
			(at -0.40005 0 90)
			(size 0 0)
			(layers "F.Cu" "F.Mask" "F.Paste")
			(net "P3V3_AUX_VDRV")
		)
		(pad "2" smd circle
			(at 0.40005 0 90)
			(size 0 0)
			(layers "F.Cu" "F.Mask" "F.Paste")
			(net "P3V3_AUX_VCC")
		)
	)
	(footprint ""
		(layer "F.Cu")
		(at 129.72288 -92.674948 90)
		(property "Reference" "R203"
			(at 0 0 90)
			(layer "F.SilkS")
			(hide yes)
			(effects
				(font
					(size 1.27 1.27)
				)
			)
		)
		(property "Value" ""
			(at 0 0 90)
			(layer "F.Fab")
			(effects
				(font
					(size 1.27 1.27)
				)
			)
		)
		(duplicate_pad_numbers_are_jumpers no)
		(fp_line
			(start 0.7874 -0.4064)
			(end 0.7874 0.4064)
			(stroke
				(width 0.1524)
				(type default)
			)
			(layer "F.SilkS")
		)
		(fp_line
			(start -0.7874 -0.4064)
			(end 0.7874 -0.4064)
			(stroke
				(width 0.1524)
				(type default)
			)
			(layer "F.SilkS")
		)
		(fp_line
			(start 0.7874 0.4064)
			(end -0.7874 0.4064)
			(stroke
				(width 0.1524)
				(type default)
			)
			(layer "F.SilkS")
		)
		(fp_line
			(start -0.7874 0.4064)
			(end -0.7874 -0.4064)
			(stroke
				(width 0.1524)
				(type default)
			)
			(layer "F.SilkS")
		)
		(fp_line
			(start -0.12065 -0.305054)
			(end -0.12065 -0.2794)
			(stroke
				(width 0.1)
				(type default)
			)
			(layer "F.Fab")
		)
		(fp_line
			(start -0.67945 -0.305054)
			(end -0.12065 -0.305054)
			(stroke
				(width 0.1)
				(type default)
			)
			(layer "F.Fab")
		)
		(fp_line
			(start 0.67945 -0.3048)
			(end 0.67945 0.3048)
			(stroke
				(width 0.1)
				(type default)
			)
			(layer "F.Fab")
		)
		(fp_line
			(start 0.12065 -0.3048)
			(end 0.67945 -0.3048)
			(stroke
				(width 0.1)
				(type default)
			)
			(layer "F.Fab")
		)
		(fp_line
			(start 0.12065 -0.2794)
			(end 0.12065 -0.3048)
			(stroke
				(width 0.1)
				(type default)
			)
			(layer "F.Fab")
		)
		(fp_line
			(start -0.12065 -0.2794)
			(end 0.12065 -0.2794)
			(stroke
				(width 0.1)
				(type default)
			)
			(layer "F.Fab")
		)
		(fp_line
			(start 0.120396 0.2794)
			(end -0.12065 0.2794)
			(stroke
				(width 0.1)
				(type default)
			)
			(layer "F.Fab")
		)
		(fp_line
			(start -0.12065 0.2794)
			(end -0.12065 0.3048)
			(stroke
				(width 0.1)
				(type default)
			)
			(layer "F.Fab")
		)
		(fp_line
			(start 0.67945 0.3048)
			(end 0.120396 0.3048)
			(stroke
				(width 0.1)
				(type default)
			)
			(layer "F.Fab")
		)
		(fp_line
			(start 0.120396 0.3048)
			(end 0.120396 0.2794)
			(stroke
				(width 0.1)
				(type default)
			)
			(layer "F.Fab")
		)
		(fp_line
			(start -0.12065 0.3048)
			(end -0.67945 0.3048)
			(stroke
				(width 0.1)
				(type default)
			)
			(layer "F.Fab")
		)
		(fp_line
			(start -0.67945 0.3048)
			(end -0.67945 -0.305054)
			(stroke
				(width 0.1)
				(type default)
			)
			(layer "F.Fab")
		)
		(pad "1" smd circle
			(at -0.40005 0 90)
			(size 0 0)
			(layers "F.Cu" "F.Mask" "F.Paste")
			(net "H_CPU0_MEMHOT_OUT_LVC1_R_N")
		)
		(pad "2" smd circle
			(at 0.40005 0 90)
			(size 0 0)
			(layers "F.Cu" "F.Mask" "F.Paste")
			(net "H_CPU0_MEMHOT_OUT_VT_R_N")
		)
	)
)
